(kicad_pcb
	(version 20260206)
	(generator "pcbnew")
	(generator_version "10.0")
	(general
		(thickness 1.6)
		(legacy_teardrops no)
	)
	(paper "A4")
	(title_block
		(title "v1-chassis-manager — T6M_CM_d_v01_1031_1645.brd")
		(comment 1 "Open CloudServer (Microsoft) / footprints 1277-1282 of 2512")
	)
	(layers
		(0 "F.Cu" signal "TOP")
		(4 "In1.Cu" signal "GND1")
		(6 "In2.Cu" signal "IN1")
		(8 "In3.Cu" signal "VCC1")
		(10 "In4.Cu" signal "VCC2")
		(12 "In5.Cu" signal "GND2")
		(14 "In6.Cu" signal "IN2")
		(16 "In7.Cu" signal "IN3")
		(18 "In8.Cu" signal "GND3")
		(2 "B.Cu" signal "BOTTOM")
		(9 "F.Adhes" user "F.Adhesive")
		(11 "B.Adhes" user "B.Adhesive")
		(13 "F.Paste" user "Package Geometry/Pastemask Top")
		(15 "B.Paste" user "Package Geometry/Pastemask Bottom")
		(5 "F.SilkS" user "Ref Des/Silkscreen Top")
		(7 "B.SilkS" user "Ref Des/Silkscreen Bottom")
		(1 "F.Mask" user "Board Geometry/Soldermask Top")
		(3 "B.Mask" user "Board Geometry/Soldermask Bottom")
		(17 "Dwgs.User" user "User.Drawings")
		(19 "Cmts.User" user "User.Comments")
		(21 "Eco1.User" user "User.Eco1")
		(23 "Eco2.User" user "User.Eco2")
		(25 "Edge.Cuts" user "Board Geometry/Outline")
		(27 "Margin" user)
		(31 "F.CrtYd" user "Package Geometry/Place Bound Top")
		(29 "B.CrtYd" user "Package Geometry/Place Bound Bottom")
		(35 "F.Fab" user "Ref Des/Assembly Top")
		(33 "B.Fab" user "Ref Des/Assembly Bottom")
	)
	(footprint ""
		(layer "F.Cu")
		(at 87.73668 -77.200252 180)
		(property "Reference" "C60"
			(at -3.937 0.021336 0)
			(unlocked yes)
			(layer "F.SilkS")
			(effects
				(font
					(size 0.7874 0.5842)
					(thickness 0.1524)
				)
			)
		)
		(property "Value" ""
			(at 0 0 180)
			(layer "F.Fab")
			(effects
				(font
					(size 1.27 1.27)
				)
			)
		)
		(duplicate_pad_numbers_are_jumpers no)
		(fp_line
			(start 1.2954 0.5842)
			(end -1.2954 0.5842)
			(stroke
				(width 0.1524)
				(type default)
			)
			(layer "F.SilkS")
		)
		(fp_line
			(start 1.2954 -0.5842)
			(end 1.2954 0.5842)
			(stroke
				(width 0.1524)
				(type default)
			)
			(layer "F.SilkS")
		)
		(fp_line
			(start 0 -0.5842)
			(end 0 0.5842)
			(stroke
				(width 0.1524)
				(type default)
			)
			(layer "F.SilkS")
		)
		(fp_line
			(start -1.2954 0.5842)
			(end -1.2954 -0.5842)
			(stroke
				(width 0.1524)
				(type default)
			)
			(layer "F.SilkS")
		)
		(fp_line
			(start -1.2954 -0.5842)
			(end 1.2954 -0.5842)
			(stroke
				(width 0.1524)
				(type default)
			)
			(layer "F.SilkS")
		)
		(fp_poly
			(pts
				(xy 0.8636 -0.4572) (xy 0.8636 -0.3556) (xy 1.143 -0.3556) (xy 1.143 0.3556) (xy 0.8636 0.3556)
				(xy 0.8636 0.4572) (xy -0.8636 0.4572) (xy -0.8636 0.3556) (xy -1.143 0.3556) (xy -1.143 -0.3556)
				(xy -0.8636 -0.3556) (xy -0.8636 -0.4572)
			)
			(stroke
				(width 0)
				(type default)
			)
			(fill no)
			(layer "F.CrtYd")
		)
		(fp_line
			(start 0.884936 0.504952)
			(end -0.884936 0.504952)
			(stroke
				(width 0.1)
				(type default)
			)
			(layer "F.Fab")
		)
		(fp_line
			(start 0.884936 -0.504952)
			(end 0.884936 0.504952)
			(stroke
				(width 0.1)
				(type default)
			)
			(layer "F.Fab")
		)
		(fp_line
			(start -0.884936 0.504952)
			(end -0.884936 -0.504952)
			(stroke
				(width 0.1)
				(type default)
			)
			(layer "F.Fab")
		)
		(fp_line
			(start -0.884936 -0.504952)
			(end 0.884936 -0.504952)
			(stroke
				(width 0.1)
				(type default)
			)
			(layer "F.Fab")
		)
		(pad "1" smd rect
			(at 0.7366 0 270)
			(size 0.7112 0.8128)
			(layers "F.Cu" "F.Mask" "F.Paste")
			(net "P1V05_VCCPLLCPU0SIO_NODE1")
		)
		(pad "2" smd rect
			(at -0.7366 0 270)
			(size 0.7112 0.8128)
			(layers "F.Cu" "F.Mask" "F.Paste")
			(net "GND")
		)
	)
	(footprint ""
		(layer "F.Cu")
		(at 148.07184 -175.28032 180)
		(property "Reference" "R794"
			(at 1.07442 2.382012 0)
			(unlocked yes)
			(layer "F.SilkS")
			(effects
				(font
					(size 0.7874 0.5842)
					(thickness 0.1524)
				)
				(justify left)
			)
		)
		(property "Value" ""
			(at 0 0 180)
			(layer "F.Fab")
			(effects
				(font
					(size 1.27 1.27)
				)
			)
		)
		(duplicate_pad_numbers_are_jumpers no)
		(fp_line
			(start 0.7874 0.4064)
			(end -0.7874 0.4064)
			(stroke
				(width 0.1524)
				(type default)
			)
			(layer "F.SilkS")
		)
		(fp_line
			(start 0.7874 -0.4064)
			(end 0.7874 0.4064)
			(stroke
				(width 0.1524)
				(type default)
			)
			(layer "F.SilkS")
		)
		(fp_line
			(start -0.7874 0.4064)
			(end -0.7874 -0.4064)
			(stroke
				(width 0.1524)
				(type default)
			)
			(layer "F.SilkS")
		)
		(fp_line
			(start -0.7874 -0.4064)
			(end 0.7874 -0.4064)
			(stroke
				(width 0.1524)
				(type default)
			)
			(layer "F.SilkS")
		)
		(fp_poly
			(pts
				(xy -0.508 0.2794) (xy -0.508 0.2286) (xy -0.635 0.2286) (xy -0.635 -0.254) (xy -0.5334 -0.254)
				(xy -0.5334 -0.2794) (xy 0.5334 -0.2794) (xy 0.5334 -0.254) (xy 0.635 -0.254) (xy 0.635 0.254) (xy 0.5334 0.254)
				(xy 0.5334 0.2794)
			)
			(stroke
				(width 0)
				(type default)
			)
			(fill no)
			(layer "F.CrtYd")
		)
		(pad "1" smd rect
			(at 0.40005 0 180)
			(size 0.4572 0.508)
			(layers "F.Cu" "F.Mask" "F.Paste")
			(net "CPLD_UART_RTS_P3_N")
		)
		(pad "2" smd rect
			(at -0.40005 0 180)
			(size 0.4572 0.508)
			(layers "F.Cu" "F.Mask" "F.Paste")
			(net "GND")
		)
	)
	(footprint ""
		(layer "F.Cu")
		(at 118.183914 -136.24814 -90)
		(property "Reference" "PR70"
			(at -2.32664 -5.267452 90)
			(unlocked yes)
			(layer "F.SilkS")
			(effects
				(font
					(size 0.635 0.4064)
					(thickness 0.1524)
				)
				(justify left)
			)
		)
		(property "Value" ""
			(at 0 0 270)
			(layer "F.Fab")
			(effects
				(font
					(size 1.27 1.27)
				)
			)
		)
		(duplicate_pad_numbers_are_jumpers no)
		(fp_line
			(start -0.7874 0.4064)
			(end -0.7874 -0.4064)
			(stroke
				(width 0.1524)
				(type default)
			)
			(layer "F.SilkS")
		)
		(fp_line
			(start 0.7874 0.4064)
			(end -0.7874 0.4064)
			(stroke
				(width 0.1524)
				(type default)
			)
			(layer "F.SilkS")
		)
		(fp_line
			(start -0.7874 -0.4064)
			(end 0.7874 -0.4064)
			(stroke
				(width 0.1524)
				(type default)
			)
			(layer "F.SilkS")
		)
		(fp_line
			(start 0.7874 -0.4064)
			(end 0.7874 0.4064)
			(stroke
				(width 0.1524)
				(type default)
			)
			(layer "F.SilkS")
		)
		(fp_poly
			(pts
				(xy -0.508 0.2794) (xy -0.508 0.2286) (xy -0.635 0.2286) (xy -0.635 -0.254) (xy -0.5334 -0.254)
				(xy -0.5334 -0.2794) (xy 0.5334 -0.2794) (xy 0.5334 -0.254) (xy 0.635 -0.254) (xy 0.635 0.254) (xy 0.5334 0.254)
				(xy 0.5334 0.2794)
			)
			(stroke
				(width 0)
				(type default)
			)
			(fill no)
			(layer "F.CrtYd")
		)
		(pad "1" smd rect
			(at 0.40005 0 270)
			(size 0.4572 0.508)
			(layers "F.Cu" "F.Mask" "F.Paste")
			(net "VR_PVCCP_NODE1_FB_RR")
		)
		(pad "2" smd rect
			(at -0.40005 0 270)
			(size 0.4572 0.508)
			(layers "F.Cu" "F.Mask" "F.Paste")
			(net "VR_PVCCP_NODE1_VSEN")
		)
	)
	(footprint ""
		(layer "F.Cu")
		(at 61.444886 -121.044462 -90)
		(property "Reference" "R323"
			(at 4.642612 -8.319516 90)
			(unlocked yes)
			(layer "F.SilkS")
			(effects
				(font
					(size 0.7874 0.5842)
					(thickness 0.1524)
				)
				(justify left)
			)
		)
		(property "Value" ""
			(at 0 0 270)
			(layer "F.Fab")
			(effects
				(font
					(size 1.27 1.27)
				)
			)
		)
		(duplicate_pad_numbers_are_jumpers no)
		(fp_line
			(start -0.7874 0.4064)
			(end -0.7874 -0.4064)
			(stroke
				(width 0.1524)
				(type default)
			)
			(layer "F.SilkS")
		)
		(fp_line
			(start 0.7874 0.4064)
			(end -0.7874 0.4064)
			(stroke
				(width 0.1524)
				(type default)
			)
			(layer "F.SilkS")
		)
		(fp_line
			(start -0.7874 -0.4064)
			(end 0.7874 -0.4064)
			(stroke
				(width 0.1524)
				(type default)
			)
			(layer "F.SilkS")
		)
		(fp_line
			(start 0.7874 -0.4064)
			(end 0.7874 0.4064)
			(stroke
				(width 0.1524)
				(type default)
			)
			(layer "F.SilkS")
		)
		(fp_poly
			(pts
				(xy -0.508 0.2794) (xy -0.508 0.2286) (xy -0.635 0.2286) (xy -0.635 -0.254) (xy -0.5334 -0.254)
				(xy -0.5334 -0.2794) (xy 0.5334 -0.2794) (xy 0.5334 -0.254) (xy 0.635 -0.254) (xy 0.635 0.254) (xy 0.5334 0.254)
				(xy 0.5334 0.2794)
			)
			(stroke
				(width 0)
				(type default)
			)
			(fill no)
			(layer "F.CrtYd")
		)
		(pad "1" smd rect
			(at 0.40005 0 270)
			(size 0.4572 0.508)
			(layers "F.Cu" "F.Mask" "F.Paste")
			(net "P3V3_NODE1")
		)
		(pad "2" smd rect
			(at -0.40005 0 270)
			(size 0.4572 0.508)
			(layers "F.Cu" "F.Mask" "F.Paste")
			(net "BMC_ROMA7")
		)
	)
	(footprint ""
		(layer "F.Cu")
		(at 19.99996 -7.799832)
		(property "Reference" "D18"
			(at -3.796284 4.463288 90)
			(unlocked yes)
			(layer "F.SilkS")
			(effects
				(font
					(size 0.7874 0.5842)
					(thickness 0.1524)
				)
				(justify left)
			)
		)
		(property "Value" ""
			(at 0 0 0)
			(layer "F.Fab")
			(effects
				(font
					(size 1.27 1.27)
				)
			)
		)
		(duplicate_pad_numbers_are_jumpers no)
		(fp_line
			(start -3.109976 -1.400048)
			(end -3.109976 1.1938)
			(stroke
				(width 0.1524)
				(type default)
			)
			(layer "F.SilkS")
		)
		(fp_line
			(start -3.109976 0.8128)
			(end -3.109976 7.739888)
			(stroke
				(width 0.1524)
				(type default)
			)
			(layer "F.SilkS")
		)
		(fp_line
			(start -3.109976 7.739888)
			(end -2.499868 7.739888)
			(stroke
				(width 0.1524)
				(type default)
			)
			(layer "F.SilkS")
		)
		(fp_line
			(start -2.499868 7.739888)
			(end -2.499868 10.24001)
			(stroke
				(width 0.1524)
				(type default)
			)
			(layer "F.SilkS")
		)
		(fp_line
			(start 2.499868 7.739888)
			(end 3.109976 7.739888)
			(stroke
				(width 0.1524)
				(type default)
			)
			(layer "F.SilkS")
		)
		(fp_line
			(start 2.499868 10.24001)
			(end 2.499868 7.739888)
			(stroke
				(width 0.1524)
				(type default)
			)
			(layer "F.SilkS")
		)
		(fp_line
			(start 3.109976 -1.400048)
			(end -3.109976 -1.400048)
			(stroke
				(width 0.1524)
				(type default)
			)
			(layer "F.SilkS")
		)
		(fp_line
			(start 3.109976 1.4478)
			(end 3.109976 -1.400048)
			(stroke
				(width 0.1524)
				(type default)
			)
			(layer "F.SilkS")
		)
		(fp_line
			(start 3.109976 7.739888)
			(end 3.109976 0.6096)
			(stroke
				(width 0.1524)
				(type default)
			)
			(layer "F.SilkS")
		)
		(fp_arc
			(start 2.499868 10.24001)
			(mid 0 12.739878)
			(end -2.499868 10.24001)
			(stroke
				(width 0.1524)
				(type default)
			)
			(layer "F.SilkS")
		)
		(fp_poly
			(pts
				(xy -1.27 -1.5494) (xy -1.778 -2.5654) (xy -0.762 -2.5654)
			)
			(stroke
				(width 0)
				(type default)
			)
			(fill yes)
			(layer "F.SilkS")
		)
		(fp_poly
			(pts
				(xy -2.0828 3.354832) (xy -2.0828 1.729232) (xy -1.4478 1.729232) (xy -1.4478 1.725168) (xy -0.4572 1.725168)
				(xy -0.4572 3.3528) (xy -1.388872 3.3528) (xy -1.388872 3.354832)
			)
			(stroke
				(width 0)
				(type default)
			)
			(fill no)
			(layer "B.CrtYd")
		)
		(fp_poly
			(pts
				(arc
					(start 0 0.8128)
					(mid 0 -0.8128)
					(end 0 0.8128)
				)
			)
			(stroke
				(width 0)
				(type default)
			)
			(fill no)
			(layer "B.CrtYd")
		)
		(fp_poly
			(pts
				(arc
					(start 1.27 3.3528)
					(mid 1.27 1.7272)
					(end 1.27 3.3528)
				)
			)
			(stroke
				(width 0)
				(type default)
			)
			(fill no)
			(layer "B.CrtYd")
		)
		(fp_poly
			(pts
				(xy -2.499868 7.739888)
				(arc
					(start -2.499868 10.24001)
					(mid 0 12.739878)
					(end 2.499868 10.24001)
				)
				(xy 2.499868 7.739888) (xy 3.109976 7.739888) (xy 3.109976 -1.400048) (xy -3.109976 -1.400048) (xy -3.109976 7.739888)
			)
			(stroke
				(width 0)
				(type default)
			)
			(fill no)
			(layer "F.CrtYd")
		)
		(fp_line
			(start -3.109976 -1.400048)
			(end -3.109976 7.739888)
			(stroke
				(width 0.1)
				(type default)
			)
			(layer "F.Fab")
		)
		(fp_line
			(start -3.109976 -1.400048)
			(end -3.109976 7.739888)
			(stroke
				(width 0.1)
				(type default)
			)
			(layer "F.Fab")
		)
		(fp_line
			(start -3.109976 7.739888)
			(end -2.499868 7.739888)
			(stroke
				(width 0.1)
				(type default)
			)
			(layer "F.Fab")
		)
		(fp_line
			(start -3.109976 7.739888)
			(end -2.499868 7.739888)
			(stroke
				(width 0.1)
				(type default)
			)
			(layer "F.Fab")
		)
		(fp_line
			(start -2.499868 7.739888)
			(end -2.499868 10.24001)
			(stroke
				(width 0.1)
				(type default)
			)
			(layer "F.Fab")
		)
		(fp_line
			(start -2.499868 7.739888)
			(end -2.499868 10.24001)
			(stroke
				(width 0.1)
				(type default)
			)
			(layer "F.Fab")
		)
		(fp_line
			(start 2.499868 7.739888)
			(end 3.109976 7.739888)
			(stroke
				(width 0.1)
				(type default)
			)
			(layer "F.Fab")
		)
		(fp_line
			(start 2.499868 7.739888)
			(end 3.109976 7.739888)
			(stroke
				(width 0.1)
				(type default)
			)
			(layer "F.Fab")
		)
		(fp_line
			(start 2.499868 10.24001)
			(end 2.499868 7.739888)
			(stroke
				(width 0.1)
				(type default)
			)
			(layer "F.Fab")
		)
		(fp_line
			(start 2.499868 10.24001)
			(end 2.499868 7.739888)
			(stroke
				(width 0.1)
				(type default)
			)
			(layer "F.Fab")
		)
		(fp_line
			(start 3.109976 -1.400048)
			(end -3.109976 -1.400048)
			(stroke
				(width 0.1)
				(type default)
			)
			(layer "F.Fab")
		)
		(fp_line
			(start 3.109976 -1.400048)
			(end -3.109976 -1.400048)
			(stroke
				(width 0.1)
				(type default)
			)
			(layer "F.Fab")
		)
		(fp_line
			(start 3.109976 7.739888)
			(end 3.109976 -1.400048)
			(stroke
				(width 0.1)
				(type default)
			)
			(layer "F.Fab")
		)
		(fp_line
			(start 3.109976 7.739888)
			(end 3.109976 -1.400048)
			(stroke
				(width 0.1)
				(type default)
			)
			(layer "F.Fab")
		)
		(fp_arc
			(start 2.499868 10.24001)
			(mid 0 12.739878)
			(end -2.499868 10.24001)
			(stroke
				(width 0.1)
				(type default)
			)
			(layer "F.Fab")
		)
		(fp_arc
			(start 2.499868 10.24001)
			(mid 0 12.739878)
			(end -2.499868 10.24001)
			(stroke
				(width 0.1)
				(type default)
			)
			(layer "F.Fab")
		)
		(fp_poly
			(pts
				(xy -1.27 -1.5494) (xy -1.778 -2.5654) (xy -0.762 -2.5654)
			)
			(stroke
				(width 0)
				(type default)
			)
			(fill yes)
			(layer "F.Fab")
		)
		(fp_text user "1"
			(at -3.782568 0.37719 0)
			(unlocked yes)
			(layer "F.SilkS")
			(effects
				(font
					(size 0.7874 0.5842)
					(thickness 0.1524)
				)
				(justify left)
			)
		)
		(fp_text user "3"
			(at 3.218942 3.372358 0)
			(unlocked yes)
			(layer "F.SilkS")
			(effects
				(font
					(size 0.7874 0.5842)
					(thickness 0.1524)
				)
				(justify left)
			)
		)
		(fp_text user "2"
			(at 3.241548 -0.785876 0)
			(unlocked yes)
			(layer "F.SilkS")
			(effects
				(font
					(size 0.7874 0.5842)
					(thickness 0.1524)
				)
				(justify left)
			)
		)
		(fp_text user "1"
			(at -3.282696 2.342134 0)
			(unlocked yes)
			(layer "B.SilkS")
			(effects
				(font
					(size 0.7874 0.5842)
					(thickness 0.1524)
				)
				(justify left mirror)
			)
		)
		(fp_text user "2"
			(at 0.574294 -2.155698 0)
			(unlocked yes)
			(layer "B.SilkS")
			(effects
				(font
					(size 0.7874 0.5842)
					(thickness 0.1524)
				)
				(justify left mirror)
			)
		)
		(fp_text user "3"
			(at 3.208528 2.271522 0)
			(unlocked yes)
			(layer "B.SilkS")
			(effects
				(font
					(size 0.7874 0.5842)
					(thickness 0.1524)
				)
				(justify left mirror)
			)
		)
		(fp_text user "1"
			(at -0.9779 1.330706 0)
			(unlocked yes)
			(layer "B.Fab")
			(effects
				(font
					(size 0.7874 0.5842)
					(thickness 0.000001)
				)
				(justify left mirror)
			)
		)
		(fp_text user "2"
			(at 0.2921 1.254506 0)
			(unlocked yes)
			(layer "B.Fab")
			(effects
				(font
					(size 0.7874 0.5842)
					(thickness 0.000001)
				)
				(justify left mirror)
			)
		)
		(fp_text user "3"
			(at 1.5621 1.330706 0)
			(unlocked yes)
			(layer "B.Fab")
			(effects
				(font
					(size 0.7874 0.5842)
					(thickness 0.000001)
				)
				(justify left mirror)
			)
		)
		(fp_text user "1"
			(at -2.1717 -2.022094 0)
			(unlocked yes)
			(layer "F.Fab")
			(effects
				(font
					(size 0.7874 0.5842)
					(thickness 0.000001)
				)
				(justify left)
			)
		)
		(fp_text user "2"
			(at -0.2921 -2.022094 0)
			(unlocked yes)
			(layer "F.Fab")
			(effects
				(font
					(size 0.7874 0.5842)
					(thickness 0.000001)
				)
				(justify left)
			)
		)
		(fp_text user "3"
			(at 0.9779 -1.996694 0)
			(unlocked yes)
			(layer "F.Fab")
			(effects
				(font
					(size 0.7874 0.5842)
					(thickness 0.000001)
				)
				(justify left)
			)
		)
		(pad "1" thru_hole rect
			(at -1.27 2.54)
			(size 1.524 1.524)
			(drill 1.016)
			(layers "*.Cu" "*.Mask")
			(remove_unused_layers no)
			(net "ATTENTION_LED_R")
			(clearance 0)
			(padstack
				(mode front_inner_back)
				(layer "Inner"
					(shape circle)
					(size 1.524 1.524)
					(clearance 0)
				)
				(layer "B.Cu"
					(shape rect)
					(size 1.524 1.524)
					(clearance 0)
				)
			)
		)
		(pad "2" thru_hole circle
			(at 0 0)
			(size 1.524 1.524)
			(drill 1.016)
			(layers "*.Cu" "*.Mask")
			(remove_unused_layers no)
			(net "N53608934")
			(clearance 0)
		)
		(pad "3" thru_hole circle
			(at 1.27 2.54)
			(size 1.524 1.524)
			(drill 1.016)
			(layers "*.Cu" "*.Mask")
			(remove_unused_layers no)
			(net "GND")
			(clearance 0)
		)
	)
	(footprint ""
		(layer "F.Cu")
		(at 171.151042 -137.351008)
		(property "Reference" "C797"
			(at -2.942082 -9.370314 0)
			(unlocked yes)
			(layer "F.SilkS")
			(effects
				(font
					(size 0.7874 0.5842)
					(thickness 0.1524)
				)
				(justify left)
			)
		)
		(property "Value" ""
			(at 0 0 0)
			(layer "F.Fab")
			(effects
				(font
					(size 1.27 1.27)
				)
			)
		)
		(duplicate_pad_numbers_are_jumpers no)
		(fp_line
			(start -0.7874 -0.4064)
			(end 0.7874 -0.4064)
			(stroke
				(width 0.1524)
				(type default)
			)
			(layer "F.SilkS")
		)
		(fp_line
			(start -0.7874 0.4064)
			(end -0.7874 -0.4064)
			(stroke
				(width 0.1524)
				(type default)
			)
			(layer "F.SilkS")
		)
		(fp_line
			(start 0 0.381)
			(end 0 -0.381)
			(stroke
				(width 0.1524)
				(type default)
			)
			(layer "F.SilkS")
		)
		(fp_line
			(start 0.7874 -0.4064)
			(end 0.7874 0.4064)
			(stroke
				(width 0.1524)
				(type default)
			)
			(layer "F.SilkS")
		)
		(fp_line
			(start 0.7874 0.4064)
			(end -0.7874 0.4064)
			(stroke
				(width 0.1524)
				(type default)
			)
			(layer "F.SilkS")
		)
		(fp_poly
			(pts
				(xy -0.5334 0.254) (xy -0.635 0.254) (xy -0.635 0.2286) (xy -0.635 -0.254) (xy -0.5334 -0.254) (xy -0.5334 -0.2794)
				(xy 0.5334 -0.2794) (xy 0.5334 -0.254) (xy 0.635 -0.254) (xy 0.635 0.254) (xy 0.5334 0.254) (xy 0.5334 0.2794)
				(xy -0.508 0.2794) (xy -0.5334 0.2794)
			)
			(stroke
				(width 0)
				(type default)
			)
			(fill no)
			(layer "F.CrtYd")
		)
		(pad "1" smd rect
			(at 0.40005 0)
			(size 0.4572 0.508)
			(layers "F.Cu" "F.Mask" "F.Paste")
			(net "GND")
		)
		(pad "2" smd rect
			(at -0.40005 0)
			(size 0.4572 0.508)
			(layers "F.Cu" "F.Mask" "F.Paste")
			(net "PWR_BTN_NODE1_L")
		)
	)
)
